(kicad_pcb
	(version 20260206)
	(generator "pcbnew")
	(generator_version "10.0")
	(general
		(thickness 1.6)
		(legacy_teardrops no)
	)
	(paper "A4")
	(title_block
		(title "Bryce Canyon_IOM_IOC_16318-2_OCP.brd")
		(comment 1 "Bryce Canyon / footprints 223-229 of 1605")
	)
	(layers
		(0 "F.Cu" signal "TOP")
		(4 "In1.Cu" signal "L2GND")
		(6 "In2.Cu" signal "L3")
		(8 "In3.Cu" signal "L4VCC")
		(10 "In4.Cu" signal "L5VCC")
		(12 "In5.Cu" signal "L6")
		(14 "In6.Cu" signal "L7GND")
		(2 "B.Cu" signal "BOTTOM")
		(9 "F.Adhes" user "F.Adhesive")
		(11 "B.Adhes" user "B.Adhesive")
		(13 "F.Paste" user "Package Geometry/Pastemask Top")
		(15 "B.Paste" user "Package Geometry/Pastemask Bottom")
		(5 "F.SilkS" user "Ref Des/Silkscreen Top")
		(7 "B.SilkS" user "Ref Des/Silkscreen Bottom")
		(1 "F.Mask" user "Board Geometry/Soldermask Top")
		(3 "B.Mask" user "Board Geometry/Soldermask Bottom")
		(17 "Dwgs.User" user "User.Drawings")
		(19 "Cmts.User" user "User.Comments")
		(21 "Eco1.User" user "User.Eco1")
		(23 "Eco2.User" user "User.Eco2")
		(25 "Edge.Cuts" user "Board Geometry/Outline")
		(27 "Margin" user)
		(31 "F.CrtYd" user "Package Geometry/Place Bound Top")
		(29 "B.CrtYd" user "Package Geometry/Place Bound Bottom")
		(35 "F.Fab" user "Ref Des/Assembly Top")
		(33 "B.Fab" user "Ref Des/Assembly Bottom")
	)
	(footprint ""
		(layer "F.Cu")
		(at 22.614636 -14.63929)
		(property "Reference" "R48"
			(at 0 0 0)
			(layer "F.SilkS")
			(hide yes)
			(effects
				(font
					(size 1.27 1.27)
				)
			)
		)
		(property "Value" "4K7R2F-GP"
			(at 0.064008 -3.993896 0)
			(unlocked yes)
			(layer "F.Fab")
			(hide yes)
			(effects
				(font
					(size 1.016 1.016)
					(thickness 0.1524)
				)
			)
		)
		(property "Device Type" "R402H16"
			(at 0.064008 -5.517896 0)
			(unlocked yes)
			(layer "F.Fab")
			(hide yes)
			(effects
				(font
					(size 1.016 1.016)
					(thickness 0.1524)
				)
			)
		)
		(duplicate_pad_numbers_are_jumpers no)
		(fp_line
			(start -0.508 -0.9398)
			(end -0.508 0.9398)
			(stroke
				(width 0.1524)
				(type default)
			)
			(layer "F.SilkS")
		)
		(fp_line
			(start 0.508 -0.9398)
			(end -0.508 -0.9398)
			(stroke
				(width 0.1524)
				(type default)
			)
			(layer "F.SilkS")
		)
		(fp_rect
			(start -0.508 0.9398)
			(end 0.508 -0.9398)
			(stroke
				(width 0)
				(type default)
			)
			(fill no)
			(layer "F.CrtYd")
		)
		(fp_rect
			(start -0.508 0.9398)
			(end 0.508 -0.9398)
			(stroke
				(width 0)
				(type default)
			)
			(fill no)
			(layer "F.Fab")
		)
		(pad "1" smd custom
			(at 0 -0.4445)
			(size 0.1397 0.1397)
			(layers "F.Cu" "F.Mask" "F.Paste")
			(net "P3V3_STBY")
			(options
				(clearance outline)
				(anchor circle)
			)
			(primitives
				(gr_poly
					(pts
						(arc
							(start -0.1778 -0.2794)
							(mid -0.249642 -0.249642)
							(end -0.2794 -0.1778)
						)
						(arc
							(start -0.2794 0.1778)
							(mid -0.249642 0.249642)
							(end -0.1778 0.2794)
						)
						(arc
							(start 0.1778 0.2794)
							(mid 0.249642 0.249642)
							(end 0.2794 0.1778)
						)
						(arc
							(start 0.2794 -0.1778)
							(mid 0.249642 -0.249642)
							(end 0.1778 -0.2794)
						)
					)
					(width 0)
					(fill yes)
				)
			)
		)
		(pad "2" smd custom
			(at 0 0.4445)
			(size 0.1397 0.1397)
			(layers "F.Cu" "F.Mask" "F.Paste")
			(net "FP_PWR_BTN_N")
			(options
				(clearance outline)
				(anchor circle)
			)
			(primitives
				(gr_poly
					(pts
						(arc
							(start -0.1778 -0.2794)
							(mid -0.249642 -0.249642)
							(end -0.2794 -0.1778)
						)
						(arc
							(start -0.2794 0.1778)
							(mid -0.249642 0.249642)
							(end -0.1778 0.2794)
						)
						(arc
							(start 0.1778 0.2794)
							(mid 0.249642 0.249642)
							(end 0.2794 0.1778)
						)
						(arc
							(start 0.2794 -0.1778)
							(mid 0.249642 -0.249642)
							(end 0.1778 -0.2794)
						)
					)
					(width 0)
					(fill yes)
				)
			)
		)
	)
	(footprint ""
		(layer "F.Cu")
		(at 94.810072 -12.502642 90)
		(property "Reference" "D14"
			(at 0 0 90)
			(layer "F.SilkS")
			(hide yes)
			(effects
				(font
					(size 1.27 1.27)
				)
			)
		)
		(property "Value" "PESD5V0S1BL-1-GP"
			(at 1.8923 -1.5621 90)
			(unlocked yes)
			(layer "F.Fab")
			(hide yes)
			(effects
				(font
					(size 1.016 1.016)
					(thickness 0.1524)
				)
			)
		)
		(property "Device Type" "SOD882-10D6-1H20"
			(at 1.8923 -3.0861 90)
			(unlocked yes)
			(layer "F.Fab")
			(hide yes)
			(effects
				(font
					(size 1.016 1.016)
					(thickness 0.1524)
				)
			)
		)
		(duplicate_pad_numbers_are_jumpers no)
		(fp_line
			(start -0.3048 -0.9271)
			(end 0.3048 -0.9271)
			(stroke
				(width 0.254)
				(type default)
			)
			(layer "F.SilkS")
		)
		(fp_rect
			(start -0.2921 0.4953)
			(end 0.2921 -0.4953)
			(stroke
				(width 0)
				(type default)
			)
			(fill no)
			(layer "F.CrtYd")
		)
		(fp_poly
			(pts
				(xy -0.4318 0.8001) (xy -0.4318 -0.266192) (xy -0.2921 -0.266192) (xy -0.2921 0.4953) (xy 0.2921 0.4953)
				(xy 0.2921 -0.4953) (xy -0.2921 -0.4953) (xy -0.2921 -0.2667) (xy -0.4318 -0.2667) (xy -0.4318 -0.8001)
				(xy 0.4318 -0.8001) (xy 0.4318 0.8001)
			)
			(stroke
				(width 0)
				(type default)
			)
			(fill no)
			(layer "F.CrtYd")
		)
		(fp_rect
			(start -0.4318 0.8001)
			(end 0.4318 -0.8001)
			(stroke
				(width 0)
				(type default)
			)
			(fill no)
			(layer "F.Fab")
		)
		(pad "1" smd custom
			(at 0 -0.4445 90)
			(size 0.1143 0.1143)
			(layers "F.Cu" "F.Mask" "F.Paste")
			(net "I2C_DEBUG_SCL")
			(options
				(clearance outline)
				(anchor circle)
			)
			(primitives
				(gr_poly
					(pts
						(arc
							(start -0.2032 0.2286)
							(mid -0.275042 0.198842)
							(end -0.3048 0.127)
						)
						(arc
							(start -0.3048 -0.127)
							(mid -0.275042 -0.198842)
							(end -0.2032 -0.2286)
						)
						(arc
							(start 0.2032 -0.2286)
							(mid 0.275042 -0.198842)
							(end 0.3048 -0.127)
						)
						(arc
							(start 0.3048 0.127)
							(mid 0.275042 0.198842)
							(end 0.2032 0.2286)
						)
					)
					(width 0)
					(fill yes)
				)
			)
		)
		(pad "2" smd custom
			(at 0 0.4445 90)
			(size 0.1143 0.1143)
			(layers "F.Cu" "F.Mask" "F.Paste")
			(net "GND")
			(options
				(clearance outline)
				(anchor circle)
			)
			(primitives
				(gr_poly
					(pts
						(arc
							(start 0.2032 -0.2286)
							(mid 0.275042 -0.198842)
							(end 0.3048 -0.127)
						)
						(arc
							(start 0.3048 0.127)
							(mid 0.275042 0.198842)
							(end 0.2032 0.2286)
						)
						(arc
							(start -0.2032 0.2286)
							(mid -0.275042 0.198842)
							(end -0.3048 0.127)
						)
						(arc
							(start -0.3048 -0.127)
							(mid -0.275042 -0.198842)
							(end -0.2032 -0.2286)
						)
					)
					(width 0)
					(fill yes)
				)
			)
		)
	)
	(footprint ""
		(layer "F.Cu")
		(at 198.4756 -113.5126 180)
		(property "Reference" "C258"
			(at 0 0 180)
			(layer "F.SilkS")
			(hide yes)
			(effects
				(font
					(size 1.27 1.27)
				)
			)
		)
		(property "Value" "SC22U6D3V6KX-2-GP"
			(at -0.0762 -5.1308 180)
			(unlocked yes)
			(layer "F.Fab")
			(hide yes)
			(effects
				(font
					(size 1.016 1.016)
					(thickness 0.1524)
				)
			)
		)
		(property "Device Type" "C1206H71"
			(at -0.127 -6.6548 180)
			(unlocked yes)
			(layer "F.Fab")
			(hide yes)
			(effects
				(font
					(size 1.016 1.016)
					(thickness 0.1524)
				)
			)
		)
		(duplicate_pad_numbers_are_jumpers no)
		(fp_line
			(start 1.016 2.2352)
			(end -1.016 2.2352)
			(stroke
				(width 0.1524)
				(type default)
			)
			(layer "F.SilkS")
		)
		(fp_line
			(start 1.016 0.8382)
			(end 1.016 2.2352)
			(stroke
				(width 0.1524)
				(type default)
			)
			(layer "F.SilkS")
		)
		(fp_line
			(start 1.016 -2.2352)
			(end 1.016 -0.8382)
			(stroke
				(width 0.1524)
				(type default)
			)
			(layer "F.SilkS")
		)
		(fp_line
			(start -1.016 2.2352)
			(end -1.016 0.8382)
			(stroke
				(width 0.1524)
				(type default)
			)
			(layer "F.SilkS")
		)
		(fp_line
			(start -1.016 -0.8382)
			(end -1.016 -2.2352)
			(stroke
				(width 0.1524)
				(type default)
			)
			(layer "F.SilkS")
		)
		(fp_line
			(start -1.016 -2.2352)
			(end 1.016 -2.2352)
			(stroke
				(width 0.1524)
				(type default)
			)
			(layer "F.SilkS")
		)
		(fp_rect
			(start -1.0922 2.3114)
			(end 1.0922 -2.3114)
			(stroke
				(width 0)
				(type default)
			)
			(fill no)
			(layer "F.CrtYd")
		)
		(fp_poly
			(pts
				(xy 1.0922 -2.3114) (xy 1.0922 2.3114) (xy -1.0922 2.3114) (xy -1.0922 -2.3114)
			)
			(stroke
				(width 0)
				(type default)
			)
			(fill no)
			(layer "F.Fab")
		)
		(pad "1" smd rect
			(at 0 -1.397 180)
			(size 1.651 1.27)
			(layers "F.Cu" "F.Mask" "F.Paste")
			(net "P0V975")
		)
		(pad "2" smd rect
			(at 0 1.397 180)
			(size 1.651 1.27)
			(layers "F.Cu" "F.Mask" "F.Paste")
			(net "GND")
		)
	)
	(footprint ""
		(layer "F.Cu")
		(at 175.006 -127.381)
		(property "Reference" "R526"
			(at 0 0 0)
			(layer "F.SilkS")
			(hide yes)
			(effects
				(font
					(size 1.27 1.27)
				)
			)
		)
		(property "Value" "4K7R2F-GP"
			(at 0.064008 -3.993896 0)
			(unlocked yes)
			(layer "F.Fab")
			(hide yes)
			(effects
				(font
					(size 1.016 1.016)
					(thickness 0.1524)
				)
			)
		)
		(property "Device Type" "R402H16"
			(at 0.064008 -5.517896 0)
			(unlocked yes)
			(layer "F.Fab")
			(hide yes)
			(effects
				(font
					(size 1.016 1.016)
					(thickness 0.1524)
				)
			)
		)
		(duplicate_pad_numbers_are_jumpers no)
		(fp_line
			(start -0.508 -0.9398)
			(end -0.508 0.9398)
			(stroke
				(width 0.1524)
				(type default)
			)
			(layer "F.SilkS")
		)
		(fp_line
			(start 0.508 -0.9398)
			(end -0.508 -0.9398)
			(stroke
				(width 0.1524)
				(type default)
			)
			(layer "F.SilkS")
		)
		(fp_rect
			(start -0.508 0.9398)
			(end 0.508 -0.9398)
			(stroke
				(width 0)
				(type default)
			)
			(fill no)
			(layer "F.CrtYd")
		)
		(fp_rect
			(start -0.508 0.9398)
			(end 0.508 -0.9398)
			(stroke
				(width 0)
				(type default)
			)
			(fill no)
			(layer "F.Fab")
		)
		(pad "1" smd custom
			(at 0 -0.4445)
			(size 0.1397 0.1397)
			(layers "F.Cu" "F.Mask" "F.Paste")
			(net "P3V3_STBY")
			(options
				(clearance outline)
				(anchor circle)
			)
			(primitives
				(gr_poly
					(pts
						(arc
							(start -0.1778 -0.2794)
							(mid -0.249642 -0.249642)
							(end -0.2794 -0.1778)
						)
						(arc
							(start -0.2794 0.1778)
							(mid -0.249642 0.249642)
							(end -0.1778 0.2794)
						)
						(arc
							(start 0.1778 0.2794)
							(mid 0.249642 0.249642)
							(end 0.2794 0.1778)
						)
						(arc
							(start 0.2794 -0.1778)
							(mid 0.249642 -0.249642)
							(end 0.1778 -0.2794)
						)
					)
					(width 0)
					(fill yes)
				)
			)
		)
		(pad "2" smd custom
			(at 0 0.4445)
			(size 0.1397 0.1397)
			(layers "F.Cu" "F.Mask" "F.Paste")
			(net "Q6_G")
			(options
				(clearance outline)
				(anchor circle)
			)
			(primitives
				(gr_poly
					(pts
						(arc
							(start -0.1778 -0.2794)
							(mid -0.249642 -0.249642)
							(end -0.2794 -0.1778)
						)
						(arc
							(start -0.2794 0.1778)
							(mid -0.249642 0.249642)
							(end -0.1778 0.2794)
						)
						(arc
							(start 0.1778 0.2794)
							(mid 0.249642 0.249642)
							(end 0.2794 0.1778)
						)
						(arc
							(start 0.2794 -0.1778)
							(mid 0.249642 -0.249642)
							(end 0.1778 -0.2794)
						)
					)
					(width 0)
					(fill yes)
				)
			)
		)
	)
	(footprint ""
		(layer "F.Cu")
		(at 91.64828 -149.488144 180)
		(property "Reference" "R24"
			(at 0 0 180)
			(layer "F.SilkS")
			(hide yes)
			(effects
				(font
					(size 1.27 1.27)
				)
			)
		)
		(property "Value" "10KR2F-2-GP"
			(at 0.064008 -3.993896 180)
			(unlocked yes)
			(layer "F.Fab")
			(hide yes)
			(effects
				(font
					(size 1.016 1.016)
					(thickness 0.1524)
				)
			)
		)
		(property "Device Type" "R402H16"
			(at 0.064008 -5.517896 180)
			(unlocked yes)
			(layer "F.Fab")
			(hide yes)
			(effects
				(font
					(size 1.016 1.016)
					(thickness 0.1524)
				)
			)
		)
		(duplicate_pad_numbers_are_jumpers no)
		(fp_line
			(start 0.508 -0.9398)
			(end -0.508 -0.9398)
			(stroke
				(width 0.1524)
				(type default)
			)
			(layer "F.SilkS")
		)
		(fp_line
			(start -0.508 -0.9398)
			(end -0.508 0.9398)
			(stroke
				(width 0.1524)
				(type default)
			)
			(layer "F.SilkS")
		)
		(fp_rect
			(start -0.508 0.9398)
			(end 0.508 -0.9398)
			(stroke
				(width 0)
				(type default)
			)
			(fill no)
			(layer "F.CrtYd")
		)
		(fp_rect
			(start -0.508 0.9398)
			(end 0.508 -0.9398)
			(stroke
				(width 0)
				(type default)
			)
			(fill no)
			(layer "F.Fab")
		)
		(pad "1" smd custom
			(at 0 -0.4445 180)
			(size 0.1397 0.1397)
			(layers "F.Cu" "F.Mask" "F.Paste")
			(net "P3V3_STBY")
			(options
				(clearance outline)
				(anchor circle)
			)
			(primitives
				(gr_poly
					(pts
						(arc
							(start -0.1778 -0.2794)
							(mid -0.249642 -0.249642)
							(end -0.2794 -0.1778)
						)
						(arc
							(start -0.2794 0.1778)
							(mid -0.249642 0.249642)
							(end -0.1778 0.2794)
						)
						(arc
							(start 0.1778 0.2794)
							(mid 0.249642 0.249642)
							(end 0.2794 0.1778)
						)
						(arc
							(start 0.2794 -0.1778)
							(mid 0.249642 -0.249642)
							(end 0.1778 -0.2794)
						)
					)
					(width 0)
					(fill yes)
				)
			)
		)
		(pad "2" smd custom
			(at 0 0.4445 180)
			(size 0.1397 0.1397)
			(layers "F.Cu" "F.Mask" "F.Paste")
			(net "USB_OCS_N1")
			(options
				(clearance outline)
				(anchor circle)
			)
			(primitives
				(gr_poly
					(pts
						(arc
							(start -0.1778 -0.2794)
							(mid -0.249642 -0.249642)
							(end -0.2794 -0.1778)
						)
						(arc
							(start -0.2794 0.1778)
							(mid -0.249642 0.249642)
							(end -0.1778 0.2794)
						)
						(arc
							(start 0.1778 0.2794)
							(mid 0.249642 0.249642)
							(end 0.2794 0.1778)
						)
						(arc
							(start 0.2794 -0.1778)
							(mid 0.249642 -0.249642)
							(end 0.1778 -0.2794)
						)
					)
					(width 0)
					(fill yes)
				)
			)
		)
	)
	(footprint ""
		(layer "F.Cu")
		(at 174.5234 -72.6186 90)
		(property "Reference" "R586"
			(at 0 0 90)
			(layer "F.SilkS")
			(hide yes)
			(effects
				(font
					(size 1.27 1.27)
				)
			)
		)
		(property "Value" "2K2R2F-GP"
			(at 0.064008 -3.993896 90)
			(unlocked yes)
			(layer "F.Fab")
			(hide yes)
			(effects
				(font
					(size 1.016 1.016)
					(thickness 0.1524)
				)
			)
		)
		(property "Device Type" "R402H16"
			(at 0.064008 -5.517896 90)
			(unlocked yes)
			(layer "F.Fab")
			(hide yes)
			(effects
				(font
					(size 1.016 1.016)
					(thickness 0.1524)
				)
			)
		)
		(duplicate_pad_numbers_are_jumpers no)
		(fp_line
			(start 0.508 -0.9398)
			(end -0.508 -0.9398)
			(stroke
				(width 0.1524)
				(type default)
			)
			(layer "F.SilkS")
		)
		(fp_line
			(start -0.508 -0.9398)
			(end -0.508 0.9398)
			(stroke
				(width 0.1524)
				(type default)
			)
			(layer "F.SilkS")
		)
		(fp_rect
			(start -0.508 0.9398)
			(end 0.508 -0.9398)
			(stroke
				(width 0)
				(type default)
			)
			(fill no)
			(layer "F.CrtYd")
		)
		(fp_rect
			(start -0.508 0.9398)
			(end 0.508 -0.9398)
			(stroke
				(width 0)
				(type default)
			)
			(fill no)
			(layer "F.Fab")
		)
		(pad "1" smd custom
			(at 0 -0.4445 90)
			(size 0.1397 0.1397)
			(layers "F.Cu" "F.Mask" "F.Paste")
			(net "P1V8")
			(options
				(clearance outline)
				(anchor circle)
			)
			(primitives
				(gr_poly
					(pts
						(arc
							(start -0.1778 -0.2794)
							(mid -0.249642 -0.249642)
							(end -0.2794 -0.1778)
						)
						(arc
							(start -0.2794 0.1778)
							(mid -0.249642 0.249642)
							(end -0.1778 0.2794)
						)
						(arc
							(start 0.1778 0.2794)
							(mid 0.249642 0.249642)
							(end 0.2794 0.1778)
						)
						(arc
							(start 0.2794 -0.1778)
							(mid 0.249642 -0.249642)
							(end 0.1778 -0.2794)
						)
					)
					(width 0)
					(fill yes)
				)
			)
		)
		(pad "2" smd custom
			(at 0 0.4445 90)
			(size 0.1397 0.1397)
			(layers "F.Cu" "F.Mask" "F.Paste")
			(net "IOC_SCL_4")
			(options
				(clearance outline)
				(anchor circle)
			)
			(primitives
				(gr_poly
					(pts
						(arc
							(start -0.1778 -0.2794)
							(mid -0.249642 -0.249642)
							(end -0.2794 -0.1778)
						)
						(arc
							(start -0.2794 0.1778)
							(mid -0.249642 0.249642)
							(end -0.1778 0.2794)
						)
						(arc
							(start 0.1778 0.2794)
							(mid 0.249642 0.249642)
							(end 0.2794 0.1778)
						)
						(arc
							(start 0.2794 -0.1778)
							(mid 0.249642 -0.249642)
							(end 0.1778 -0.2794)
						)
					)
					(width 0)
					(fill yes)
				)
			)
		)
	)
	(footprint ""
		(layer "F.Cu")
		(at 132.0546 -26.2001)
		(property "Reference" "TP2"
			(at 0 0 0)
			(layer "F.SilkS")
			(hide yes)
			(effects
				(font
					(size 1.27 1.27)
				)
			)
		)
		(property "Value" "TPAD28-2-GP"
			(at -0.0127 -1.6637 0)
			(unlocked yes)
			(layer "F.Fab")
			(hide yes)
			(effects
				(font
					(size 1.016 1.016)
					(thickness 0.1524)
				)
			)
		)
		(property "Device Type" "TPAD28"
			(at -0.0127 -3.1877 0)
			(unlocked yes)
			(layer "F.Fab")
			(hide yes)
			(effects
				(font
					(size 1.016 1.016)
					(thickness 0.1524)
				)
			)
		)
		(duplicate_pad_numbers_are_jumpers no)
		(fp_poly
			(pts
				(arc
					(start 0.3556 0)
					(mid -0.3556 0)
					(end 0.3556 0)
				)
			)
			(stroke
				(width 0)
				(type default)
			)
			(fill no)
			(layer "F.CrtYd")
		)
		(fp_poly
			(pts
				(arc
					(start 0.6096 0)
					(mid -0.6096 0)
					(end 0.6096 0)
				)
			)
			(stroke
				(width 0)
				(type default)
			)
			(fill no)
			(layer "F.Fab")
		)
		(pad "1" smd circle
			(at 0 0)
			(size 0.7112 0.7112)
			(layers "F.Cu" "F.Mask" "F.Paste")
			(net "PCIE_COMP_TO_IOM_CLK_3_DP")
		)
	)
)
